(kicad_pcb
	(version 20260206)
	(generator "pcbnew")
	(generator_version "10.0")
	(general
		(thickness 1.6)
		(legacy_teardrops no)
	)
	(paper "A4")
	(title_block
		(title "panther-plus-userver — 13130-1b_20150205.brd")
		(comment 1 "Honey Badger (Wiwynn) / footprint 894 of 1509 (DIMM1), pads 114-120 of 210")
	)
	(layers
		(0 "F.Cu" signal "TOP")
		(4 "In1.Cu" signal "L2")
		(6 "In2.Cu" signal "L3")
		(8 "In3.Cu" signal "L4")
		(10 "In4.Cu" signal "L5")
		(12 "In5.Cu" signal "L6")
		(14 "In6.Cu" signal "L7")
		(16 "In7.Cu" signal "L8")
		(18 "In8.Cu" signal "L9")
		(20 "In9.Cu" signal "L10")
		(22 "In10.Cu" signal "L11")
		(2 "B.Cu" signal "BOTTOM")
		(9 "F.Adhes" user "F.Adhesive")
		(11 "B.Adhes" user "B.Adhesive")
		(13 "F.Paste" user "Package Geometry/Pastemask Top")
		(15 "B.Paste" user "Package Geometry/Pastemask Bottom")
		(5 "F.SilkS" user "Ref Des/Silkscreen Top")
		(7 "B.SilkS" user "Ref Des/Silkscreen Bottom")
		(1 "F.Mask" user "Board Geometry/Soldermask Top")
		(3 "B.Mask" user "Board Geometry/Soldermask Bottom")
		(17 "Dwgs.User" user "User.Drawings")
		(19 "Cmts.User" user "User.Comments")
		(21 "Eco1.User" user "User.Eco1")
		(23 "Eco2.User" user "User.Eco2")
		(25 "Edge.Cuts" user "Board Geometry/Outline")
		(27 "Margin" user)
		(31 "F.CrtYd" user "Package Geometry/Place Bound Top")
		(29 "B.CrtYd" user "Package Geometry/Place Bound Bottom")
		(35 "F.Fab" user "Ref Des/Assembly Top")
		(33 "B.Fab" user "Ref Des/Assembly Bottom")
	)
	(footprint ""
		(layer "B.Cu")
		(at 158.500064 -66.699892 180)
		(property "Reference" "DIMM1"
			(at 0 0 0)
			(layer "B.SilkS")
			(hide yes)
			(effects
				(font
					(size 1.27 1.27)
				)
				(justify mirror)
			)
		)
		(property "Value" "DDR3-204P-142-COLAY-1-GP-U"
			(at 41.312338 -16.676878 180)
			(unlocked yes)
			(layer "B.Fab")
			(hide yes)
			(effects
				(font
					(size 1.016 1.016)
					(thickness 0.1524)
				)
				(justify mirror)
			)
		)
		(property "Device Type" "AS0A626-J8R6-7H-COLAY-1"
			(at 41.312338 -18.200878 180)
			(unlocked yes)
			(layer "B.Fab")
			(hide yes)
			(effects
				(font
					(size 1.016 1.016)
					(thickness 0.1524)
				)
				(justify mirror)
			)
		)
		(duplicate_pad_numbers_are_jumpers no)
		(pad "112" smd custom
			(at 4.05003 4.100068)
			(size 0.1143 0.1143)
			(layers "B.Cu" "B.Mask" "B.Paste")
			(net "M_A_CK_DP1")
			(options
				(clearance outline)
				(anchor circle)
			)
			(primitives
				(gr_poly
					(pts
						(xy 0 -0.9017) (xy -0.03175 -0.89916) (xy -0.0635 -0.889) (xy -0.09144 -0.87376) (xy -0.11684 -0.85344)
						(xy -0.13716 -0.82804) (xy -0.1524 -0.8001) (xy -0.16256 -0.76835) (xy -0.1651 -0.7366) (xy -0.1651 -0.11938)
						(xy -0.17272 -0.11176) (xy -0.19812 -0.0762) (xy -0.2032 -0.06604) (xy -0.20701 -0.05715) (xy -0.21209 -0.04699)
						(xy -0.2159 -0.03683) (xy -0.21844 -0.02667) (xy -0.22225 -0.01524) (xy -0.22352 -0.00508) (xy -0.22606 0.00508)
						(xy -0.22733 0.01651) (xy -0.22733 0.02667) (xy -0.2286 0.0381) (xy -0.22733 0.04953) (xy -0.22733 0.05969)
						(xy -0.22606 0.07112) (xy -0.22352 0.08128) (xy -0.22225 0.09144) (xy -0.21844 0.10287) (xy -0.2159 0.11303)
						(xy -0.21209 0.12319) (xy -0.20701 0.13335) (xy -0.2032 0.14224) (xy -0.19812 0.1524) (xy -0.17272 0.18796)
						(xy -0.1651 0.19558) (xy -0.1651 0.7366) (xy -0.16256 0.76835) (xy -0.1524 0.8001) (xy -0.13716 0.82804)
						(xy -0.11684 0.85344) (xy -0.09144 0.87376) (xy -0.0635 0.889) (xy -0.03175 0.89916) (xy 0 0.9017)
						(xy 0.03175 0.89916) (xy 0.0635 0.889) (xy 0.09144 0.87376) (xy 0.11684 0.85344) (xy 0.13716 0.82804)
						(xy 0.1524 0.8001) (xy 0.16256 0.76835) (xy 0.1651 0.7366) (xy 0.1651 0.19685) (xy 0.17272 0.18923)
						(xy 0.17907 0.18034) (xy 0.18669 0.17145) (xy 0.19177 0.16256) (xy 0.19812 0.15367) (xy 0.20828 0.13335)
						(xy 0.21971 0.10287) (xy 0.22225 0.09271) (xy 0.22479 0.08128) (xy 0.22606 0.07112) (xy 0.2286 0.05969)
						(xy 0.2286 0.01651) (xy 0.22606 0.00508) (xy 0.22479 -0.00508) (xy 0.22225 -0.01651) (xy 0.21971 -0.02667)
						(xy 0.20828 -0.05715) (xy 0.19812 -0.07747) (xy 0.19177 -0.08636) (xy 0.18669 -0.09525) (xy 0.17907 -0.10414)
						(xy 0.17272 -0.11303) (xy 0.1651 -0.12065) (xy 0.1651 -0.7366) (xy 0.16256 -0.76835) (xy 0.1524 -0.8001)
						(xy 0.13716 -0.82804) (xy 0.11684 -0.85344) (xy 0.09144 -0.87376) (xy 0.0635 -0.889) (xy 0.03175 -0.89916)
					)
					(width 0)
					(fill yes)
				)
			)
		)
		(pad "113" smd custom
			(at 4.350004 -4.100068)
			(size 0.1143 0.1143)
			(layers "B.Cu" "B.Mask" "B.Paste")
			(net "M_A_CK_DN0")
			(options
				(clearance outline)
				(anchor circle)
			)
			(primitives
				(gr_poly
					(pts
						(xy 0 -0.9017) (xy -0.03175 -0.89916) (xy -0.0635 -0.889) (xy -0.09144 -0.87376) (xy -0.11684 -0.85344)
						(xy -0.13716 -0.82804) (xy -0.1524 -0.8001) (xy -0.16256 -0.76835) (xy -0.1651 -0.7366) (xy -0.1651 -0.44958)
						(xy -0.17272 -0.44196) (xy -0.19812 -0.4064) (xy -0.2032 -0.39624) (xy -0.20701 -0.38735) (xy -0.21209 -0.37719)
						(xy -0.2159 -0.36703) (xy -0.21844 -0.35687) (xy -0.22225 -0.34544) (xy -0.22352 -0.33528) (xy -0.22606 -0.32512)
						(xy -0.22733 -0.31369) (xy -0.22733 -0.30353) (xy -0.2286 -0.2921) (xy -0.22733 -0.28067) (xy -0.22733 -0.27051)
						(xy -0.22606 -0.25908) (xy -0.22352 -0.24892) (xy -0.22225 -0.23876) (xy -0.21844 -0.22733) (xy -0.2159 -0.21717)
						(xy -0.21209 -0.20701) (xy -0.20701 -0.19685) (xy -0.2032 -0.18796) (xy -0.19812 -0.1778) (xy -0.17272 -0.14224)
						(xy -0.1651 -0.13462) (xy -0.1651 0.7366) (xy -0.16256 0.76835) (xy -0.1524 0.8001) (xy -0.13716 0.82804)
						(xy -0.11684 0.85344) (xy -0.09144 0.87376) (xy -0.0635 0.889) (xy -0.03175 0.89916) (xy 0 0.9017)
						(xy 0.03175 0.89916) (xy 0.0635 0.889) (xy 0.09144 0.87376) (xy 0.11684 0.85344) (xy 0.13716 0.82804)
						(xy 0.1524 0.8001) (xy 0.16256 0.76835) (xy 0.1651 0.7366) (xy 0.1651 -0.13462) (xy 0.17272 -0.14224)
						(xy 0.19812 -0.1778) (xy 0.2032 -0.18796) (xy 0.20701 -0.19685) (xy 0.21209 -0.20701) (xy 0.2159 -0.21717)
						(xy 0.21844 -0.22733) (xy 0.22225 -0.23876) (xy 0.22352 -0.24892) (xy 0.22606 -0.25908) (xy 0.22733 -0.27051)
						(xy 0.22733 -0.28067) (xy 0.2286 -0.2921) (xy 0.22733 -0.30353) (xy 0.22733 -0.31369) (xy 0.22606 -0.32512)
						(xy 0.22352 -0.33528) (xy 0.22225 -0.34544) (xy 0.21844 -0.35687) (xy 0.2159 -0.36703) (xy 0.21209 -0.37719)
						(xy 0.20701 -0.38735) (xy 0.2032 -0.39624) (xy 0.19812 -0.4064) (xy 0.17272 -0.44196) (xy 0.1651 -0.44958)
						(xy 0.1651 -0.7366) (xy 0.16256 -0.76835) (xy 0.1524 -0.8001) (xy 0.13716 -0.82804) (xy 0.11684 -0.85344)
						(xy 0.09144 -0.87376) (xy 0.0635 -0.889) (xy 0.03175 -0.89916)
					)
					(width 0)
					(fill yes)
				)
			)
		)
		(pad "114" smd custom
			(at 4.649978 4.100068)
			(size 0.1143 0.1143)
			(layers "B.Cu" "B.Mask" "B.Paste")
			(net "M_A_CK_DN1")
			(options
				(clearance outline)
				(anchor circle)
			)
			(primitives
				(gr_poly
					(pts
						(xy 0 -0.9017) (xy -0.03175 -0.89916) (xy -0.0635 -0.889) (xy -0.09144 -0.87376) (xy -0.11684 -0.85344)
						(xy -0.13716 -0.82804) (xy -0.1524 -0.8001) (xy -0.16256 -0.76835) (xy -0.1651 -0.7366) (xy -0.1651 0.13462)
						(xy -0.17272 0.14224) (xy -0.19812 0.1778) (xy -0.2032 0.18796) (xy -0.20701 0.19685) (xy -0.21209 0.20701)
						(xy -0.2159 0.21717) (xy -0.21844 0.22733) (xy -0.22225 0.23876) (xy -0.22352 0.24892) (xy -0.22606 0.25908)
						(xy -0.22733 0.27051) (xy -0.22733 0.28067) (xy -0.2286 0.2921) (xy -0.22733 0.30353) (xy -0.22733 0.31369)
						(xy -0.22606 0.32512) (xy -0.22352 0.33528) (xy -0.22225 0.34544) (xy -0.21844 0.35687) (xy -0.2159 0.36703)
						(xy -0.21209 0.37719) (xy -0.20701 0.38735) (xy -0.2032 0.39624) (xy -0.19812 0.4064) (xy -0.17272 0.44196)
						(xy -0.1651 0.44958) (xy -0.1651 0.7366) (xy -0.16256 0.76835) (xy -0.1524 0.8001) (xy -0.13716 0.82804)
						(xy -0.11684 0.85344) (xy -0.09144 0.87376) (xy -0.0635 0.889) (xy -0.03175 0.89916) (xy 0 0.9017)
						(xy 0.03175 0.89916) (xy 0.0635 0.889) (xy 0.09144 0.87376) (xy 0.11684 0.85344) (xy 0.13716 0.82804)
						(xy 0.1524 0.8001) (xy 0.16256 0.76835) (xy 0.1651 0.7366) (xy 0.1651 0.44958) (xy 0.17272 0.44196)
						(xy 0.19812 0.4064) (xy 0.2032 0.39624) (xy 0.20701 0.38735) (xy 0.21209 0.37719) (xy 0.2159 0.36703)
						(xy 0.21844 0.35687) (xy 0.22225 0.34544) (xy 0.22352 0.33528) (xy 0.22606 0.32512) (xy 0.22733 0.31369)
						(xy 0.22733 0.30353) (xy 0.2286 0.2921) (xy 0.22733 0.28067) (xy 0.22733 0.27051) (xy 0.22606 0.25908)
						(xy 0.22352 0.24892) (xy 0.22225 0.23876) (xy 0.21844 0.22733) (xy 0.2159 0.21717) (xy 0.21209 0.20701)
						(xy 0.20701 0.19685) (xy 0.2032 0.18796) (xy 0.19812 0.1778) (xy 0.17272 0.14224) (xy 0.1651 0.13462)
						(xy 0.1651 -0.7366) (xy 0.16256 -0.76835) (xy 0.1524 -0.8001) (xy 0.13716 -0.82804) (xy 0.11684 -0.85344)
						(xy 0.09144 -0.87376) (xy 0.0635 -0.889) (xy 0.03175 -0.89916)
					)
					(width 0)
					(fill yes)
				)
			)
		)
		(pad "115" smd custom
			(at 4.949952 -4.100068)
			(size 0.1143 0.1143)
			(layers "B.Cu" "B.Mask" "B.Paste")
			(net "PV_VDDR")
			(options
				(clearance outline)
				(anchor circle)
			)
			(primitives
				(gr_poly
					(pts
						(xy 0 -0.9017) (xy -0.03175 -0.89916) (xy -0.0635 -0.889) (xy -0.09144 -0.87376) (xy -0.11684 -0.85344)
						(xy -0.13716 -0.82804) (xy -0.1524 -0.8001) (xy -0.16256 -0.76835) (xy -0.1651 -0.7366) (xy -0.1651 -0.19685)
						(xy -0.17272 -0.18923) (xy -0.17907 -0.18034) (xy -0.18669 -0.17145) (xy -0.19177 -0.16256) (xy -0.19812 -0.15367)
						(xy -0.20828 -0.13335) (xy -0.21971 -0.10287) (xy -0.22225 -0.09271) (xy -0.22479 -0.08128) (xy -0.22606 -0.07112)
						(xy -0.2286 -0.05969) (xy -0.2286 -0.01651) (xy -0.22606 -0.00508) (xy -0.22479 0.00508) (xy -0.22225 0.01651)
						(xy -0.21971 0.02667) (xy -0.20828 0.05715) (xy -0.19812 0.07747) (xy -0.19177 0.08636) (xy -0.18669 0.09525)
						(xy -0.17907 0.10414) (xy -0.17272 0.11303) (xy -0.1651 0.12065) (xy -0.1651 0.7366) (xy -0.16256 0.76835)
						(xy -0.1524 0.8001) (xy -0.13716 0.82804) (xy -0.11684 0.85344) (xy -0.09144 0.87376) (xy -0.0635 0.889)
						(xy -0.03175 0.89916) (xy 0 0.9017) (xy 0.03175 0.89916) (xy 0.0635 0.889) (xy 0.09144 0.87376)
						(xy 0.11684 0.85344) (xy 0.13716 0.82804) (xy 0.1524 0.8001) (xy 0.16256 0.76835) (xy 0.1651 0.7366)
						(xy 0.1651 0.11938) (xy 0.17272 0.11176) (xy 0.19812 0.0762) (xy 0.2032 0.06604) (xy 0.20701 0.05715)
						(xy 0.21209 0.04699) (xy 0.2159 0.03683) (xy 0.21844 0.02667) (xy 0.22225 0.01524) (xy 0.22352 0.00508)
						(xy 0.22606 -0.00508) (xy 0.22733 -0.01651) (xy 0.22733 -0.02667) (xy 0.2286 -0.0381) (xy 0.22733 -0.04953)
						(xy 0.22733 -0.05969) (xy 0.22606 -0.07112) (xy 0.22352 -0.08128) (xy 0.22225 -0.09144) (xy 0.21844 -0.10287)
						(xy 0.2159 -0.11303) (xy 0.21209 -0.12319) (xy 0.20701 -0.13335) (xy 0.2032 -0.14224) (xy 0.19812 -0.1524)
						(xy 0.17272 -0.18796) (xy 0.1651 -0.19558) (xy 0.1651 -0.7366) (xy 0.16256 -0.76835) (xy 0.1524 -0.8001)
						(xy 0.13716 -0.82804) (xy 0.11684 -0.85344) (xy 0.09144 -0.87376) (xy 0.0635 -0.889) (xy 0.03175 -0.89916)
					)
					(width 0)
					(fill yes)
				)
			)
		)
		(pad "116" smd custom
			(at 5.249926 4.100068)
			(size 0.1143 0.1143)
			(layers "B.Cu" "B.Mask" "B.Paste")
			(net "PV_VDDR")
			(options
				(clearance outline)
				(anchor circle)
			)
			(primitives
				(gr_poly
					(pts
						(xy 0 -0.9017) (xy -0.03175 -0.89916) (xy -0.0635 -0.889) (xy -0.09144 -0.87376) (xy -0.11684 -0.85344)
						(xy -0.13716 -0.82804) (xy -0.1524 -0.8001) (xy -0.16256 -0.76835) (xy -0.1651 -0.7366) (xy -0.1651 -0.11938)
						(xy -0.17272 -0.11176) (xy -0.19812 -0.0762) (xy -0.2032 -0.06604) (xy -0.20701 -0.05715) (xy -0.21209 -0.04699)
						(xy -0.2159 -0.03683) (xy -0.21844 -0.02667) (xy -0.22225 -0.01524) (xy -0.22352 -0.00508) (xy -0.22606 0.00508)
						(xy -0.22733 0.01651) (xy -0.22733 0.02667) (xy -0.2286 0.0381) (xy -0.22733 0.04953) (xy -0.22733 0.05969)
						(xy -0.22606 0.07112) (xy -0.22352 0.08128) (xy -0.22225 0.09144) (xy -0.21844 0.10287) (xy -0.2159 0.11303)
						(xy -0.21209 0.12319) (xy -0.20701 0.13335) (xy -0.2032 0.14224) (xy -0.19812 0.1524) (xy -0.17272 0.18796)
						(xy -0.1651 0.19558) (xy -0.1651 0.7366) (xy -0.16256 0.76835) (xy -0.1524 0.8001) (xy -0.13716 0.82804)
						(xy -0.11684 0.85344) (xy -0.09144 0.87376) (xy -0.0635 0.889) (xy -0.03175 0.89916) (xy 0 0.9017)
						(xy 0.03175 0.89916) (xy 0.0635 0.889) (xy 0.09144 0.87376) (xy 0.11684 0.85344) (xy 0.13716 0.82804)
						(xy 0.1524 0.8001) (xy 0.16256 0.76835) (xy 0.1651 0.7366) (xy 0.1651 0.19685) (xy 0.17272 0.18923)
						(xy 0.17907 0.18034) (xy 0.18669 0.17145) (xy 0.19177 0.16256) (xy 0.19812 0.15367) (xy 0.20828 0.13335)
						(xy 0.21971 0.10287) (xy 0.22225 0.09271) (xy 0.22479 0.08128) (xy 0.22606 0.07112) (xy 0.2286 0.05969)
						(xy 0.2286 0.01651) (xy 0.22606 0.00508) (xy 0.22479 -0.00508) (xy 0.22225 -0.01651) (xy 0.21971 -0.02667)
						(xy 0.20828 -0.05715) (xy 0.19812 -0.07747) (xy 0.19177 -0.08636) (xy 0.18669 -0.09525) (xy 0.17907 -0.10414)
						(xy 0.17272 -0.11303) (xy 0.1651 -0.12065) (xy 0.1651 -0.7366) (xy 0.16256 -0.76835) (xy 0.1524 -0.8001)
						(xy 0.13716 -0.82804) (xy 0.11684 -0.85344) (xy 0.09144 -0.87376) (xy 0.0635 -0.889) (xy 0.03175 -0.89916)
					)
					(width 0)
					(fill yes)
				)
			)
		)
		(pad "117" smd custom
			(at 5.5499 -4.100068)
			(size 0.1143 0.1143)
			(layers "B.Cu" "B.Mask" "B.Paste")
			(net "M_A_MA10")
			(options
				(clearance outline)
				(anchor circle)
			)
			(primitives
				(gr_poly
					(pts
						(xy 0 -0.9017) (xy -0.03175 -0.89916) (xy -0.0635 -0.889) (xy -0.09144 -0.87376) (xy -0.11684 -0.85344)
						(xy -0.13716 -0.82804) (xy -0.1524 -0.8001) (xy -0.16256 -0.76835) (xy -0.1651 -0.7366) (xy -0.1651 -0.44958)
						(xy -0.17272 -0.44196) (xy -0.19812 -0.4064) (xy -0.2032 -0.39624) (xy -0.20701 -0.38735) (xy -0.21209 -0.37719)
						(xy -0.2159 -0.36703) (xy -0.21844 -0.35687) (xy -0.22225 -0.34544) (xy -0.22352 -0.33528) (xy -0.22606 -0.32512)
						(xy -0.22733 -0.31369) (xy -0.22733 -0.30353) (xy -0.2286 -0.2921) (xy -0.22733 -0.28067) (xy -0.22733 -0.27051)
						(xy -0.22606 -0.25908) (xy -0.22352 -0.24892) (xy -0.22225 -0.23876) (xy -0.21844 -0.22733) (xy -0.2159 -0.21717)
						(xy -0.21209 -0.20701) (xy -0.20701 -0.19685) (xy -0.2032 -0.18796) (xy -0.19812 -0.1778) (xy -0.17272 -0.14224)
						(xy -0.1651 -0.13462) (xy -0.1651 0.7366) (xy -0.16256 0.76835) (xy -0.1524 0.8001) (xy -0.13716 0.82804)
						(xy -0.11684 0.85344) (xy -0.09144 0.87376) (xy -0.0635 0.889) (xy -0.03175 0.89916) (xy 0 0.9017)
						(xy 0.03175 0.89916) (xy 0.0635 0.889) (xy 0.09144 0.87376) (xy 0.11684 0.85344) (xy 0.13716 0.82804)
						(xy 0.1524 0.8001) (xy 0.16256 0.76835) (xy 0.1651 0.7366) (xy 0.1651 -0.13462) (xy 0.17272 -0.14224)
						(xy 0.19812 -0.1778) (xy 0.2032 -0.18796) (xy 0.20701 -0.19685) (xy 0.21209 -0.20701) (xy 0.2159 -0.21717)
						(xy 0.21844 -0.22733) (xy 0.22225 -0.23876) (xy 0.22352 -0.24892) (xy 0.22606 -0.25908) (xy 0.22733 -0.27051)
						(xy 0.22733 -0.28067) (xy 0.2286 -0.2921) (xy 0.22733 -0.30353) (xy 0.22733 -0.31369) (xy 0.22606 -0.32512)
						(xy 0.22352 -0.33528) (xy 0.22225 -0.34544) (xy 0.21844 -0.35687) (xy 0.2159 -0.36703) (xy 0.21209 -0.37719)
						(xy 0.20701 -0.38735) (xy 0.2032 -0.39624) (xy 0.19812 -0.4064) (xy 0.17272 -0.44196) (xy 0.1651 -0.44958)
						(xy 0.1651 -0.7366) (xy 0.16256 -0.76835) (xy 0.1524 -0.8001) (xy 0.13716 -0.82804) (xy 0.11684 -0.85344)
						(xy 0.09144 -0.87376) (xy 0.0635 -0.889) (xy 0.03175 -0.89916)
					)
					(width 0)
					(fill yes)
				)
			)
		)
		(pad "118" smd custom
			(at 5.849874 4.100068)
			(size 0.1143 0.1143)
			(layers "B.Cu" "B.Mask" "B.Paste")
			(net "Net_16")
			(options
				(clearance outline)
				(anchor circle)
			)
			(primitives
				(gr_poly
					(pts
						(xy 0 -0.9017) (xy -0.03175 -0.89916) (xy -0.0635 -0.889) (xy -0.09144 -0.87376) (xy -0.11684 -0.85344)
						(xy -0.13716 -0.82804) (xy -0.1524 -0.8001) (xy -0.16256 -0.76835) (xy -0.1651 -0.7366) (xy -0.1651 0.13462)
						(xy -0.17272 0.14224) (xy -0.19812 0.1778) (xy -0.2032 0.18796) (xy -0.20701 0.19685) (xy -0.21209 0.20701)
						(xy -0.2159 0.21717) (xy -0.21844 0.22733) (xy -0.22225 0.23876) (xy -0.22352 0.24892) (xy -0.22606 0.25908)
						(xy -0.22733 0.27051) (xy -0.22733 0.28067) (xy -0.2286 0.2921) (xy -0.22733 0.30353) (xy -0.22733 0.31369)
						(xy -0.22606 0.32512) (xy -0.22352 0.33528) (xy -0.22225 0.34544) (xy -0.21844 0.35687) (xy -0.2159 0.36703)
						(xy -0.21209 0.37719) (xy -0.20701 0.38735) (xy -0.2032 0.39624) (xy -0.19812 0.4064) (xy -0.17272 0.44196)
						(xy -0.1651 0.44958) (xy -0.1651 0.7366) (xy -0.16256 0.76835) (xy -0.1524 0.8001) (xy -0.13716 0.82804)
						(xy -0.11684 0.85344) (xy -0.09144 0.87376) (xy -0.0635 0.889) (xy -0.03175 0.89916) (xy 0 0.9017)
						(xy 0.03175 0.89916) (xy 0.0635 0.889) (xy 0.09144 0.87376) (xy 0.11684 0.85344) (xy 0.13716 0.82804)
						(xy 0.1524 0.8001) (xy 0.16256 0.76835) (xy 0.1651 0.7366) (xy 0.1651 0.44958) (xy 0.17272 0.44196)
						(xy 0.19812 0.4064) (xy 0.2032 0.39624) (xy 0.20701 0.38735) (xy 0.21209 0.37719) (xy 0.2159 0.36703)
						(xy 0.21844 0.35687) (xy 0.22225 0.34544) (xy 0.22352 0.33528) (xy 0.22606 0.32512) (xy 0.22733 0.31369)
						(xy 0.22733 0.30353) (xy 0.2286 0.2921) (xy 0.22733 0.28067) (xy 0.22733 0.27051) (xy 0.22606 0.25908)
						(xy 0.22352 0.24892) (xy 0.22225 0.23876) (xy 0.21844 0.22733) (xy 0.2159 0.21717) (xy 0.21209 0.20701)
						(xy 0.20701 0.19685) (xy 0.2032 0.18796) (xy 0.19812 0.1778) (xy 0.17272 0.14224) (xy 0.1651 0.13462)
						(xy 0.1651 -0.7366) (xy 0.16256 -0.76835) (xy 0.1524 -0.8001) (xy 0.13716 -0.82804) (xy 0.11684 -0.85344)
						(xy 0.09144 -0.87376) (xy 0.0635 -0.889) (xy 0.03175 -0.89916)
					)
					(width 0)
					(fill yes)
				)
			)
		)
	)
)
